# S9S_MB_2U (Grand Teton) — schematic netlist excerpt (pin names and nets, part order shuffled) for the footprints in the layout excerpt that follows; sources: Cadence DE-HDL packaged netlist, KiCad conversion of 03242023_DA0F0TMBIJ0_F0T_Motherboard_J_brd_V01_OCP.brd

J17  SCONN288_ADR50017P130CC  SCONN288_ADR50017-P130CC IO  pkg DDR288S_1-1VXB  page 98
  VIN_BULK0  = P12V_S3_AUX_CPU1_NVDIMM
  RFU0  = TP_CHA_CPU1_DIMM1_FRU_0
  VIN_MGMT  = P3V3_AUX
  HSCL  = I3C_SPD_DDRABCD_CPU1_LVC1_SCL_R
  HSDA  = I3C_SPD_DDRABCD_CPU1_LVC1_SDA
  VSS0  = GND
  DQ0_A  = M_A_CPU1_SA_DQ<0>
  VSS1  = GND
  DQ1_A  = M_A_CPU1_SA_DQ<1>
  VSS2  = GND
  DQS0_A_T  = M_A_CPU1_SA_DQS_DP<0>
  DQS0_A_C  = M_A_CPU1_SA_DQS_DN<0>
  VSS3  = GND
  DQ4_A  = M_A_CPU1_SA_DQ<4>
  VSS4  = GND
  DQ5_A  = M_A_CPU1_SA_DQ<5>
  VSS5  = GND
  DQ8_A  = M_A_CPU1_SA_DQ<8>
  VSS6  = GND
  DQ9_A  = M_A_CPU1_SA_DQ<9>
  VSS7  = GND
  DQS1_A_T  = M_A_CPU1_SA_DQS_DP<1>
  DQS1_A_C  = M_A_CPU1_SA_DQS_DN<1>
  VSS8  = GND
  DQ12_A  = M_A_CPU1_SA_DQ<12>
  VSS9  = GND
  DQ13_A  = M_A_CPU1_SA_DQ<13>
  VSS10  = GND
  DQ16_A  = M_A_CPU1_SA_DQ<16>
  VSS11  = GND
  DQ17_A  = M_A_CPU1_SA_DQ<17>
  VSS12  = GND
  DQS2_A_T  = M_A_CPU1_SA_DQS_DP<2>
  DQS2_A_C  = M_A_CPU1_SA_DQS_DN<2>
  VSS13  = GND
  DQ20_A  = M_A_CPU1_SA_DQ<20>
  VSS14  = GND
  DQ21_A  = M_A_CPU1_SA_DQ<21>
  VSS15  = GND
  DQ24_A  = M_A_CPU1_SA_DQ<24>
  VSS16  = GND
  DQ25_A  = M_A_CPU1_SA_DQ<25>
  VSS17  = GND
  DQS3_A_T  = M_A_CPU1_SA_DQS_DP<3>
  DQS3_A_C  = M_A_CPU1_SA_DQS_DN<3>
  VSS18  = GND
  DQ28_A  = M_A_CPU1_SA_DQ<28>
  VSS19  = GND
  DQ29_A  = M_A_CPU1_SA_DQ<29>
  VSS20  = GND
  CB0_A  = M_A_CPU1_SA_CB<0>
  VSS21  = GND
  CB1_A  = M_A_CPU1_SA_CB<1>
  VSS22  = GND
  DQS4_A_T  = M_A_CPU1_SA_DQS_DP<4>
  DQS4_A_C  = M_A_CPU1_SA_DQS_DN<4>
  VSS23  = GND
  CB4_A  = M_A_CPU1_SA_CB<4>
  VSS24  = GND
  CB5_A  = M_A_CPU1_SA_CB<5>
  VSS25  = GND
  ALERT_N  = M_A_CPU1_ALERT_N
  VSS26  = GND
  CS0_A_N  = M_A_CPU1_SA_CS_N<0>
  VSS27  = GND
  CA0_A  = M_A_CPU1_SA_CA<0>
  VSS28  = GND
  CA2_A  = M_A_CPU1_SA_CA<2>
  VSS29  = GND
  CA4_A  = M_A_CPU1_SA_CA<4>
  VSS30  = GND
  CA6_A  = M_A_CPU1_SA_CA<6>
  VSS31  = GND
  PAR_A  = M_A_CPU1_SA_PAR
  VSS32  = GND
  CA0_B  = M_A_CPU1_SB_CA<0>
  VSS33  = GND
  CA2_B  = M_A_CPU1_SB_CA<2>
  VSS34  = GND
  CA4_B  = M_A_CPU1_SB_CA<4>
  VSS35  = GND
  CA6_B  = M_A_CPU1_SB_CA<6>
  VSS36  = GND
  CS0_B_N  = M_A_CPU1_SB_CS_N<0>
  VSS37  = GND
  \lbd||rsp_a_n\  = M_A_CPU1_SA_RSP<0>
  \lbs||rsp_b_n\  = M_A_CPU1_SB_RSP<0>
  VSS38  = GND
  CB4_B  = M_A_CPU1_SB_CB<4>
  VSS39  = GND
  CB5_B  = M_A_CPU1_SB_CB<5>
  VSS40  = GND
  \dqs9_b_t||tdqs9_b_t||dbi4_b_n\  = M_A_CPU1_SB_DQS_DP<9>
  \dqs9_b_c||tdqs9_b_c\  = M_A_CPU1_SB_DQS_DN<9>
  VSS41  = GND
  CB0_B  = M_A_CPU1_SB_CB<0>
  VSS42  = GND
  CB1_B  = M_A_CPU1_SB_CB<1>
  VSS43  = GND
  DQ0_B  = M_A_CPU1_SB_DQ<0>
  VSS44  = GND
  DQ1_B  = M_A_CPU1_SB_DQ<1>
  VSS45  = GND
  DQS0_B_T  = M_A_CPU1_SB_DQS_DP<0>
  DQS0_B_C  = M_A_CPU1_SB_DQS_DN<0>
  VSS46  = GND
  DQ4_B  = M_A_CPU1_SB_DQ<4>
  VSS47  = GND
  DQ5_B  = M_A_CPU1_SB_DQ<5>
  VSS48  = GND
  DQ8_B  = M_A_CPU1_SB_DQ<8>
  VSS49  = GND
  DQ9_B  = M_A_CPU1_SB_DQ<9>
  VSS50  = GND
  DQS1_B_T  = M_A_CPU1_SB_DQS_DP<1>
  DQS1_B_C  = M_A_CPU1_SB_DQS_DN<1>
  VSS51  = GND
  DQ12_B  = M_A_CPU1_SB_DQ<12>
  VSS52  = GND
  DQ13_B  = M_A_CPU1_SB_DQ<13>
  VSS53  = GND
  DQ16_B  = M_A_CPU1_SB_DQ<16>
  VSS54  = GND
  DQ17_B  = M_A_CPU1_SB_DQ<17>
  VSS55  = GND
  DQS2_B_T  = M_A_CPU1_SB_DQS_DP<2>
  DQS2_B_C  = M_A_CPU1_SB_DQS_DN<2>
  VSS56  = GND
  DQ20_B  = M_A_CPU1_SB_DQ<20>
  VSS57  = GND
  DQ21_B  = M_A_CPU1_SB_DQ<21>
  VSS58  = GND
  DQ24_B  = M_A_CPU1_SB_DQ<24>
  VSS59  = GND
  DQ25_B  = M_A_CPU1_SB_DQ<25>
  VSS60  = GND
  DQS3_B_T  = M_A_CPU1_SB_DQS_DP<3>
  DQS3_B_C  = M_A_CPU1_SB_DQS_DN<3>
  VSS61  = GND
  DQ28_B  = M_A_CPU1_SB_DQ<28>
  VSS62  = GND
  DQ29_B  = M_A_CPU1_SB_DQ<29>
  VSS63  = GND
  RFU1  = TP_CHA_CPU1_DIMM1_FRU_1
  VIN_BULK1  = P12V_S3_AUX_CPU1_NVDIMM
  VIN_BULK2  = P12V_S3_AUX_CPU1_NVDIMM
  \pwr_good||fail_n\  = PWRGD_CHA_CPU1_DIMM1
  HSA  = PD_CHA_CPU1_DIMM1_SAA
  RFU2  = TP_CHA_CPU1_DIMM1_FRU_2
  RFU3  = TP_CHA_CPU1_DIMM1_FRU_3
  VSS64  = GND
  DQ2_A  = M_A_CPU1_SA_DQ<2>
  VSS65  = GND
  DQ3_A  = M_A_CPU1_SA_DQ<3>
  VSS66  = GND
  \dqs5_a_c||tdqs5_a_c||dqs5_a_t||tdqs5_a_t\  = M_A_CPU1_SA_DQS_DN<5>
  \dqs5_a_t||tdqs5_a_t\  = M_A_CPU1_SA_DQS_DP<5>
  VSS67  = GND
  DQ6_A  = M_A_CPU1_SA_DQ<6>
  VSS68  = GND
  DQ7_A  = M_A_CPU1_SA_DQ<7>
  VSS69  = GND
  DQ10_A  = M_A_CPU1_SA_DQ<10>
  VSS70  = GND
  DQ11_A  = M_A_CPU1_SA_DQ<11>
  VSS71  = GND
  \dqs6_a_c||tdqs6_a_c||dqs6_a_t||tdqs6_a_t\  = M_A_CPU1_SA_DQS_DN<6>
  \dqs6_a_t||tdqs6_a_t\  = M_A_CPU1_SA_DQS_DP<6>
  VSS72  = GND
  DQ14_A  = M_A_CPU1_SA_DQ<14>
  VSS73  = GND
  DQ15_A  = M_A_CPU1_SA_DQ<15>
  VSS74  = GND
  DQ18_A  = M_A_CPU1_SA_DQ<18>
  VSS75  = GND
  DQ19_A  = M_A_CPU1_SA_DQ<19>
  VSS76  = GND
  \dqs7_a_c||tdqs7_a_c\  = M_A_CPU1_SA_DQS_DN<7>
  \dqs7_a_t||tdqs7_a_t\  = M_A_CPU1_SA_DQS_DP<7>
  VSS77  = GND
  DQ22_A  = M_A_CPU1_SA_DQ<22>
  VSS78  = GND
  DQ23_A  = M_A_CPU1_SA_DQ<23>
  VSS79  = GND
  DQ26_A  = M_A_CPU1_SA_DQ<26>
  VSS80  = GND
  DQ27_A  = M_A_CPU1_SA_DQ<27>
  VSS81  = GND
  \dqs8_a_c||tdqs8_a_c\  = M_A_CPU1_SA_DQS_DN<8>
  \dqs8_a_t||tdqs8_a_t\  = M_A_CPU1_SA_DQS_DP<8>
  VSS82  = GND
  DQ30_A  = M_A_CPU1_SA_DQ<30>
  VSS83  = GND
  DQ31_A  = M_A_CPU1_SA_DQ<31>
  VSS84  = GND
  CB2_A  = M_A_CPU1_SA_CB<2>
  VSS85  = GND
  CB3_A  = M_A_CPU1_SA_CB<3>
  VSS86  = GND
  \dqs9_a_c||tdqs9_a_c\  = M_A_CPU1_SA_DQS_DN<9>
  \dqs9_a_t||tdqs9_a_t\  = M_A_CPU1_SA_DQS_DP<9>
  VSS87  = GND
  CB6_A  = M_A_CPU1_SA_CB<6>
  VSS88  = GND
  CB7_A  = M_A_CPU1_SA_CB<7>
  VSS89  = GND
  RESET_N  = RST_M_AB_CPU1_FPGA_N
  VSS90  = GND
  CS1_A_N  = M_A_CPU1_SA_CS_N<1>
  VSS91  = GND
  CA1_A  = M_A_CPU1_SA_CA<1>
  VSS92  = GND
  CA3_A  = M_A_CPU1_SA_CA<3>
  VSS93  = GND
  CA5_A  = M_A_CPU1_SA_CA<5>
  VSS94  = GND
  CK_T  = M_A_CPU1_CLK_DP<0>
  CK_C  = M_A_CPU1_CLK_DN<0>
  VSS95  = GND
  RFU4  = TP_CHA_CPU1_DIMM1_FRU_4
  CA1_B  = M_A_CPU1_SB_CA<1>
  VSS96  = GND
  CA3_B  = M_A_CPU1_SB_CA<3>
  VSS97  = GND
  CA5_B  = M_A_CPU1_SB_CA<5>
  VSS98  = GND
  PAR_B  = M_A_CPU1_SB_PAR
  VSS99  = GND
  CS1_B_N  = M_A_CPU1_SB_CS_N<1>
  VSS100  = GND
  RFU5  = TP_CHA_CPU1_DIMM1_FRU_5
  RFU6  = TP_CHA_CPU1_DIMM1_FRU_6
  VSS101  = GND
  CB6_B  = M_A_CPU1_SB_CB<6>
  VSS102  = GND
  CB7_B  = M_A_CPU1_SB_CB<7>
  VSS103  = GND
  DQS4_B_C  = M_A_CPU1_SB_DQS_DN<4>
  DQS4_B_T  = M_A_CPU1_SB_DQS_DP<4>
  VSS104  = GND
  CB2_B  = M_A_CPU1_SB_CB<2>
  VSS105  = GND
  CB3_B  = M_A_CPU1_SB_CB<3>
  VSS106  = GND
  DQ2_B  = M_A_CPU1_SB_DQ<2>
  VSS107  = GND
  DQ3_B  = M_A_CPU1_SB_DQ<3>
  VSS108  = GND
  \dqs5_b_c||tdqs5_b_c\  = M_A_CPU1_SB_DQS_DN<5>
  \dqs5_b_t||tdqs5_b_t\  = M_A_CPU1_SB_DQS_DP<5>
  VSS109  = GND
  DQ6_B  = M_A_CPU1_SB_DQ<6>
  VSS110  = GND
  DQ7_B  = M_A_CPU1_SB_DQ<7>
  VSS111  = GND
  DQ10_B  = M_A_CPU1_SB_DQ<10>
  VSS112  = GND
  DQ11_B  = M_A_CPU1_SB_DQ<11>
  VSS113  = GND
  \dqs6_b_c||tdqs6_b_c\  = M_A_CPU1_SB_DQS_DN<6>
  \dqs6_b_t||tdqs6_b_t\  = M_A_CPU1_SB_DQS_DP<6>
  VSS114  = GND
  DQ14_B  = M_A_CPU1_SB_DQ<14>
  VSS115  = GND
  DQ15_B  = M_A_CPU1_SB_DQ<15>
  VSS116  = GND
  DQ18_B  = M_A_CPU1_SB_DQ<18>
  VSS117  = GND
  DQ19_B  = M_A_CPU1_SB_DQ<19>
  VSS118  = GND
  \dqs7_b_c||tdqs7_b_c\  = M_A_CPU1_SB_DQS_DN<7>
  \dqs7_b_t||tdqs7_b_t\  = M_A_CPU1_SB_DQS_DP<7>
  VSS119  = GND
  DQ22_B  = M_A_CPU1_SB_DQ<22>
  VSS120  = GND
  DQ23_B  = M_A_CPU1_SB_DQ<23>
  VSS121  = GND
  DQ26_B  = M_A_CPU1_SB_DQ<26>
  VSS122  = GND
  DQ27_B  = M_A_CPU1_SB_DQ<27>
  VSS123  = GND
  \dqs8_b_c||tdqs8_b_c\  = M_A_CPU1_SB_DQS_DN<8>
  \dqs8_b_t||tdqs8_b_t\  = M_A_CPU1_SB_DQS_DP<8>
  VSS124  = GND
  DQ30_B  = M_A_CPU1_SB_DQ<30>
  VSS125  = GND
  DQ31_B  = M_A_CPU1_SB_DQ<31>
  VSS126  = GND
  G1  = GND
  G2  = GND
  G3  = GND

(kicad_pcb
	(version 20260206)
	(generator "pcbnew")
	(generator_version "10.0")
	(general
		(thickness 1.6)
		(legacy_teardrops no)
	)
	(paper "A4")
	(title_block
		(title "03242023_DA0F0TMBIJ0_F0T_Motherboard_J_brd_V01_OCP.brd")
		(comment 1 "Grand Teton / footprint 1335 of 6105 (J17), pads 1-45 of 291")
	)
	(layers
		(0 "F.Cu" signal "TOP")
		(4 "In1.Cu" signal "GND")
		(6 "In2.Cu" signal "IN1")
		(8 "In3.Cu" signal "GND1")
		(10 "In4.Cu" signal "IN2")
		(12 "In5.Cu" signal "GND2")
		(14 "In6.Cu" signal "IN3")
		(16 "In7.Cu" signal "GND3")
		(18 "In8.Cu" signal "VCC")
		(20 "In9.Cu" signal "VCC1")
		(22 "In10.Cu" signal "GND4")
		(24 "In11.Cu" signal "IN4")
		(26 "In12.Cu" signal "GND5")
		(28 "In13.Cu" signal "IN5")
		(30 "In14.Cu" signal "GND6")
		(32 "In15.Cu" signal "IN6")
		(34 "In16.Cu" signal "GND7")
		(2 "B.Cu" signal "BOTTOM")
		(9 "F.Adhes" user "F.Adhesive")
		(11 "B.Adhes" user "B.Adhesive")
		(13 "F.Paste" user "Package Geometry/Pastemask Top")
		(15 "B.Paste" user "Package Geometry/Pastemask Bottom")
		(5 "F.SilkS" user "Ref Des/Silkscreen Top")
		(7 "B.SilkS" user "Ref Des/Silkscreen Bottom")
		(1 "F.Mask" user "Board Geometry/Soldermask Top")
		(3 "B.Mask" user "Board Geometry/Soldermask Bottom")
		(17 "Dwgs.User" user "User.Drawings")
		(19 "Cmts.User" user "User.Comments")
		(21 "Eco1.User" user "User.Eco1")
		(23 "Eco2.User" user "User.Eco2")
		(25 "Edge.Cuts" user "Board Geometry/Outline")
		(27 "Margin" user)
		(31 "F.CrtYd" user "Package Geometry/Place Bound Top")
		(29 "B.CrtYd" user "Package Geometry/Place Bound Bottom")
		(35 "F.Fab" user "Ref Des/Assembly Top")
		(33 "B.Fab" user "Ref Des/Assembly Bottom")
	)
	(footprint ""
		(layer "F.Cu")
		(at 55.45328 -258.091686)
		(property "Reference" "J17"
			(at -0.178562 -81.717134 0)
			(unlocked yes)
			(layer "F.SilkS")
			(effects
				(font
					(size 0.7874 0.5842)
					(thickness 0.1524)
				)
				(justify left)
			)
		)
		(property "Value" ""
			(at 0 0 0)
			(layer "F.Fab")
			(effects
				(font
					(size 1.27 1.27)
				)
			)
		)
		(duplicate_pad_numbers_are_jumpers no)
		(pad "1" smd rect
			(at -2.050034 -63.324994 270)
			(size 0.519938 1.4986)
			(layers "F.Cu" "F.Mask" "F.Paste")
			(net "P12V_S3_AUX_CPU1_NVDIMM")
		)
		(pad "2" smd rect
			(at -2.050034 -62.47511 270)
			(size 0.519938 1.4986)
			(layers "F.Cu" "F.Mask" "F.Paste")
			(net "TP_CHA_CPU1_DIMM1_FRU_0")
		)
		(pad "3" smd rect
			(at -2.050034 -61.624972 270)
			(size 0.519938 1.4986)
			(layers "F.Cu" "F.Mask" "F.Paste")
			(net "P3V3_AUX")
		)
		(pad "4" smd rect
			(at -2.050034 -60.775088 270)
			(size 0.519938 1.4986)
			(layers "F.Cu" "F.Mask" "F.Paste")
			(net "I3C_SPD_DDRABCD_CPU1_LVC1_SCL_R")
		)
		(pad "5" smd rect
			(at -2.050034 -59.92495 270)
			(size 0.519938 1.4986)
			(layers "F.Cu" "F.Mask" "F.Paste")
			(net "I3C_SPD_DDRABCD_CPU1_LVC1_SDA")
		)
		(pad "6" smd rect
			(at -2.050034 -59.075066 270)
			(size 0.519938 1.4986)
			(layers "F.Cu" "F.Mask" "F.Paste")
			(net "GND")
		)
		(pad "7" smd rect
			(at -2.050034 -58.224928 270)
			(size 0.519938 1.4986)
			(layers "F.Cu" "F.Mask" "F.Paste")
			(net "M_A_CPU1_SA_DQ<0>")
		)
		(pad "8" smd rect
			(at -2.050034 -57.375044 270)
			(size 0.519938 1.4986)
			(layers "F.Cu" "F.Mask" "F.Paste")
			(net "GND")
		)
		(pad "9" smd rect
			(at -2.050034 -56.524906 270)
			(size 0.519938 1.4986)
			(layers "F.Cu" "F.Mask" "F.Paste")
			(net "M_A_CPU1_SA_DQ<1>")
		)
		(pad "10" smd rect
			(at -2.050034 -55.675022 270)
			(size 0.519938 1.4986)
			(layers "F.Cu" "F.Mask" "F.Paste")
			(net "GND")
		)
		(pad "11" smd rect
			(at -2.050034 -54.824884 270)
			(size 0.519938 1.4986)
			(layers "F.Cu" "F.Mask" "F.Paste")
			(net "M_A_CPU1_SA_DQS_DP<0>")
		)
		(pad "12" smd rect
			(at -2.050034 -53.975 270)
			(size 0.519938 1.4986)
			(layers "F.Cu" "F.Mask" "F.Paste")
			(net "M_A_CPU1_SA_DQS_DN<0>")
		)
		(pad "13" smd rect
			(at -2.050034 -53.125116 270)
			(size 0.519938 1.4986)
			(layers "F.Cu" "F.Mask" "F.Paste")
			(net "GND")
		)
		(pad "14" smd rect
			(at -2.050034 -52.274978 270)
			(size 0.519938 1.4986)
			(layers "F.Cu" "F.Mask" "F.Paste")
			(net "M_A_CPU1_SA_DQ<4>")
		)
		(pad "15" smd rect
			(at -2.050034 -51.425094 270)
			(size 0.519938 1.4986)
			(layers "F.Cu" "F.Mask" "F.Paste")
			(net "GND")
		)
		(pad "16" smd rect
			(at -2.050034 -50.574956 270)
			(size 0.519938 1.4986)
			(layers "F.Cu" "F.Mask" "F.Paste")
			(net "M_A_CPU1_SA_DQ<5>")
		)
		(pad "17" smd rect
			(at -2.050034 -49.725072 270)
			(size 0.519938 1.4986)
			(layers "F.Cu" "F.Mask" "F.Paste")
			(net "GND")
		)
		(pad "18" smd rect
			(at -2.050034 -48.874934 270)
			(size 0.519938 1.4986)
			(layers "F.Cu" "F.Mask" "F.Paste")
			(net "M_A_CPU1_SA_DQ<8>")
		)
		(pad "19" smd rect
			(at -2.050034 -48.02505 270)
			(size 0.519938 1.4986)
			(layers "F.Cu" "F.Mask" "F.Paste")
			(net "GND")
		)
		(pad "20" smd rect
			(at -2.050034 -47.174912 270)
			(size 0.519938 1.4986)
			(layers "F.Cu" "F.Mask" "F.Paste")
			(net "M_A_CPU1_SA_DQ<9>")
		)
		(pad "21" smd rect
			(at -2.050034 -46.325028 270)
			(size 0.519938 1.4986)
			(layers "F.Cu" "F.Mask" "F.Paste")
			(net "GND")
		)
		(pad "22" smd rect
			(at -2.050034 -45.47489 270)
			(size 0.519938 1.4986)
			(layers "F.Cu" "F.Mask" "F.Paste")
			(net "M_A_CPU1_SA_DQS_DP<1>")
		)
		(pad "23" smd rect
			(at -2.050034 -44.625006 270)
			(size 0.519938 1.4986)
			(layers "F.Cu" "F.Mask" "F.Paste")
			(net "M_A_CPU1_SA_DQS_DN<1>")
		)
		(pad "24" smd rect
			(at -2.050034 -43.775122 270)
			(size 0.519938 1.4986)
			(layers "F.Cu" "F.Mask" "F.Paste")
			(net "GND")
		)
		(pad "25" smd rect
			(at -2.050034 -42.924984 270)
			(size 0.519938 1.4986)
			(layers "F.Cu" "F.Mask" "F.Paste")
			(net "M_A_CPU1_SA_DQ<12>")
		)
		(pad "26" smd rect
			(at -2.050034 -42.0751 270)
			(size 0.519938 1.4986)
			(layers "F.Cu" "F.Mask" "F.Paste")
			(net "GND")
		)
		(pad "27" smd rect
			(at -2.050034 -41.224962 270)
			(size 0.519938 1.4986)
			(layers "F.Cu" "F.Mask" "F.Paste")
			(net "M_A_CPU1_SA_DQ<13>")
		)
		(pad "28" smd rect
			(at -2.050034 -40.375078 270)
			(size 0.519938 1.4986)
			(layers "F.Cu" "F.Mask" "F.Paste")
			(net "GND")
		)
		(pad "29" smd rect
			(at -2.050034 -39.52494 270)
			(size 0.519938 1.4986)
			(layers "F.Cu" "F.Mask" "F.Paste")
			(net "M_A_CPU1_SA_DQ<16>")
		)
		(pad "30" smd rect
			(at -2.050034 -38.675056 270)
			(size 0.519938 1.4986)
			(layers "F.Cu" "F.Mask" "F.Paste")
			(net "GND")
		)
		(pad "31" smd rect
			(at -2.050034 -37.824918 270)
			(size 0.519938 1.4986)
			(layers "F.Cu" "F.Mask" "F.Paste")
			(net "M_A_CPU1_SA_DQ<17>")
		)
		(pad "32" smd rect
			(at -2.050034 -36.975034 270)
			(size 0.519938 1.4986)
			(layers "F.Cu" "F.Mask" "F.Paste")
			(net "GND")
		)
		(pad "33" smd rect
			(at -2.050034 -36.124896 270)
			(size 0.519938 1.4986)
			(layers "F.Cu" "F.Mask" "F.Paste")
			(net "M_A_CPU1_SA_DQS_DP<2>")
		)
		(pad "34" smd rect
			(at -2.050034 -35.275012 270)
			(size 0.519938 1.4986)
			(layers "F.Cu" "F.Mask" "F.Paste")
			(net "M_A_CPU1_SA_DQS_DN<2>")
		)
		(pad "35" smd rect
			(at -2.050034 -34.425128 270)
			(size 0.519938 1.4986)
			(layers "F.Cu" "F.Mask" "F.Paste")
			(net "GND")
		)
		(pad "36" smd rect
			(at -2.050034 -33.57499 270)
			(size 0.519938 1.4986)
			(layers "F.Cu" "F.Mask" "F.Paste")
			(net "M_A_CPU1_SA_DQ<20>")
		)
		(pad "37" smd rect
			(at -2.050034 -32.725106 270)
			(size 0.519938 1.4986)
			(layers "F.Cu" "F.Mask" "F.Paste")
			(net "GND")
		)
		(pad "38" smd rect
			(at -2.050034 -31.874968 270)
			(size 0.519938 1.4986)
			(layers "F.Cu" "F.Mask" "F.Paste")
			(net "M_A_CPU1_SA_DQ<21>")
		)
		(pad "39" smd rect
			(at -2.050034 -31.025084 270)
			(size 0.519938 1.4986)
			(layers "F.Cu" "F.Mask" "F.Paste")
			(net "GND")
		)
		(pad "40" smd rect
			(at -2.050034 -30.174946 270)
			(size 0.519938 1.4986)
			(layers "F.Cu" "F.Mask" "F.Paste")
			(net "M_A_CPU1_SA_DQ<24>")
		)
		(pad "41" smd rect
			(at -2.050034 -29.325062 270)
			(size 0.519938 1.4986)
			(layers "F.Cu" "F.Mask" "F.Paste")
			(net "GND")
		)
		(pad "42" smd rect
			(at -2.050034 -28.474924 270)
			(size 0.519938 1.4986)
			(layers "F.Cu" "F.Mask" "F.Paste")
			(net "M_A_CPU1_SA_DQ<25>")
		)
		(pad "43" smd rect
			(at -2.050034 -27.62504 270)
			(size 0.519938 1.4986)
			(layers "F.Cu" "F.Mask" "F.Paste")
			(net "GND")
		)
		(pad "44" smd rect
			(at -2.050034 -26.774902 270)
			(size 0.519938 1.4986)
			(layers "F.Cu" "F.Mask" "F.Paste")
			(net "M_A_CPU1_SA_DQS_DP<3>")
		)
		(pad "45" smd rect
			(at -2.050034 -25.925018 270)
			(size 0.519938 1.4986)
			(layers "F.Cu" "F.Mask" "F.Paste")
			(net "M_A_CPU1_SA_DQS_DN<3>")
		)
	)
)
